(kicad_pcb
	(version 20260206)
	(generator "pcbnew")
	(generator_version "10.0")
	(general
		(thickness 1.6)
		(legacy_teardrops no)
	)
	(paper "A4")
	(title_block
		(title "Bryce Canyon_IOM_M2_16342-2_OCP.brd")
		(comment 1 "Bryce Canyon / footprints 313-320 of 1146")
	)
	(layers
		(0 "F.Cu" signal "TOP")
		(4 "In1.Cu" signal "L2GND")
		(6 "In2.Cu" signal "L3")
		(8 "In3.Cu" signal "L4VCC")
		(10 "In4.Cu" signal "L5VCC")
		(12 "In5.Cu" signal "L6")
		(14 "In6.Cu" signal "L7GND")
		(2 "B.Cu" signal "BOTTOM")
		(9 "F.Adhes" user "F.Adhesive")
		(11 "B.Adhes" user "B.Adhesive")
		(13 "F.Paste" user "Package Geometry/Pastemask Top")
		(15 "B.Paste" user "Package Geometry/Pastemask Bottom")
		(5 "F.SilkS" user "Ref Des/Silkscreen Top")
		(7 "B.SilkS" user "Ref Des/Silkscreen Bottom")
		(1 "F.Mask" user "Board Geometry/Soldermask Top")
		(3 "B.Mask" user "Board Geometry/Soldermask Bottom")
		(17 "Dwgs.User" user "User.Drawings")
		(19 "Cmts.User" user "User.Comments")
		(21 "Eco1.User" user "User.Eco1")
		(23 "Eco2.User" user "User.Eco2")
		(25 "Edge.Cuts" user "Board Geometry/Outline")
		(27 "Margin" user)
		(31 "F.CrtYd" user "Package Geometry/Place Bound Top")
		(29 "B.CrtYd" user "Package Geometry/Place Bound Bottom")
		(35 "F.Fab" user "Ref Des/Assembly Top")
		(33 "B.Fab" user "Ref Des/Assembly Bottom")
	)
	(footprint ""
		(layer "F.Cu")
		(at 62.9666 -156.2354 180)
		(property "Reference" "R387"
			(at 0 0 180)
			(layer "F.SilkS")
			(hide yes)
			(effects
				(font
					(size 1.27 1.27)
				)
			)
		)
		(property "Value" "4K7R2F-GP"
			(at 0.064008 -3.993896 180)
			(unlocked yes)
			(layer "F.Fab")
			(hide yes)
			(effects
				(font
					(size 1.016 1.016)
					(thickness 0.1524)
				)
			)
		)
		(property "Device Type" "R402H16"
			(at 0.064008 -5.517896 180)
			(unlocked yes)
			(layer "F.Fab")
			(hide yes)
			(effects
				(font
					(size 1.016 1.016)
					(thickness 0.1524)
				)
			)
		)
		(duplicate_pad_numbers_are_jumpers no)
		(fp_line
			(start 0.508 -0.9398)
			(end -0.508 -0.9398)
			(stroke
				(width 0.1524)
				(type default)
			)
			(layer "F.SilkS")
		)
		(fp_line
			(start -0.508 -0.9398)
			(end -0.508 0.9398)
			(stroke
				(width 0.1524)
				(type default)
			)
			(layer "F.SilkS")
		)
		(fp_rect
			(start -0.508 0.9398)
			(end 0.508 -0.9398)
			(stroke
				(width 0)
				(type default)
			)
			(fill no)
			(layer "F.CrtYd")
		)
		(fp_rect
			(start -0.508 0.9398)
			(end 0.508 -0.9398)
			(stroke
				(width 0)
				(type default)
			)
			(fill no)
			(layer "F.Fab")
		)
		(pad "1" smd custom
			(at 0 -0.4445 180)
			(size 0.1397 0.1397)
			(layers "F.Cu" "F.Mask" "F.Paste")
			(net "GND")
			(options
				(clearance outline)
				(anchor circle)
			)
			(primitives
				(gr_poly
					(pts
						(arc
							(start -0.1778 -0.2794)
							(mid -0.249642 -0.249642)
							(end -0.2794 -0.1778)
						)
						(arc
							(start -0.2794 0.1778)
							(mid -0.249642 0.249642)
							(end -0.1778 0.2794)
						)
						(arc
							(start 0.1778 0.2794)
							(mid 0.249642 0.249642)
							(end 0.2794 0.1778)
						)
						(arc
							(start 0.2794 -0.1778)
							(mid 0.249642 -0.249642)
							(end 0.1778 -0.2794)
						)
					)
					(width 0)
					(fill yes)
				)
			)
		)
		(pad "2" smd custom
			(at 0 0.4445 180)
			(size 0.1397 0.1397)
			(layers "F.Cu" "F.Mask" "F.Paste")
			(net "NCSI_TXD1")
			(options
				(clearance outline)
				(anchor circle)
			)
			(primitives
				(gr_poly
					(pts
						(arc
							(start -0.1778 -0.2794)
							(mid -0.249642 -0.249642)
							(end -0.2794 -0.1778)
						)
						(arc
							(start -0.2794 0.1778)
							(mid -0.249642 0.249642)
							(end -0.1778 0.2794)
						)
						(arc
							(start 0.1778 0.2794)
							(mid 0.249642 0.249642)
							(end 0.2794 0.1778)
						)
						(arc
							(start 0.2794 -0.1778)
							(mid 0.249642 -0.249642)
							(end 0.1778 -0.2794)
						)
					)
					(width 0)
					(fill yes)
				)
			)
		)
	)
	(footprint ""
		(layer "F.Cu")
		(at 60.246006 -168.317418 90)
		(property "Reference" "R77"
			(at 0 0 90)
			(layer "F.SilkS")
			(hide yes)
			(effects
				(font
					(size 1.27 1.27)
				)
			)
		)
		(property "Value" "10KR2F-2-GP"
			(at 0.064008 -3.993896 90)
			(unlocked yes)
			(layer "F.Fab")
			(hide yes)
			(effects
				(font
					(size 1.016 1.016)
					(thickness 0.1524)
				)
			)
		)
		(property "Device Type" "R402H16"
			(at 0.064008 -5.517896 90)
			(unlocked yes)
			(layer "F.Fab")
			(hide yes)
			(effects
				(font
					(size 1.016 1.016)
					(thickness 0.1524)
				)
			)
		)
		(duplicate_pad_numbers_are_jumpers no)
		(fp_line
			(start 0.508 -0.9398)
			(end -0.508 -0.9398)
			(stroke
				(width 0.1524)
				(type default)
			)
			(layer "F.SilkS")
		)
		(fp_line
			(start -0.508 -0.9398)
			(end -0.508 0.9398)
			(stroke
				(width 0.1524)
				(type default)
			)
			(layer "F.SilkS")
		)
		(fp_rect
			(start -0.508 0.9398)
			(end 0.508 -0.9398)
			(stroke
				(width 0)
				(type default)
			)
			(fill no)
			(layer "F.CrtYd")
		)
		(fp_rect
			(start -0.508 0.9398)
			(end 0.508 -0.9398)
			(stroke
				(width 0)
				(type default)
			)
			(fill no)
			(layer "F.Fab")
		)
		(pad "1" smd custom
			(at 0 -0.4445 90)
			(size 0.1397 0.1397)
			(layers "F.Cu" "F.Mask" "F.Paste")
			(net "P3V3_STBY")
			(options
				(clearance outline)
				(anchor circle)
			)
			(primitives
				(gr_poly
					(pts
						(arc
							(start -0.1778 -0.2794)
							(mid -0.249642 -0.249642)
							(end -0.2794 -0.1778)
						)
						(arc
							(start -0.2794 0.1778)
							(mid -0.249642 0.249642)
							(end -0.1778 0.2794)
						)
						(arc
							(start 0.1778 0.2794)
							(mid 0.249642 0.249642)
							(end 0.2794 0.1778)
						)
						(arc
							(start 0.2794 -0.1778)
							(mid 0.249642 -0.249642)
							(end 0.1778 -0.2794)
						)
					)
					(width 0)
					(fill yes)
				)
			)
		)
		(pad "2" smd custom
			(at 0 0.4445 90)
			(size 0.1397 0.1397)
			(layers "F.Cu" "F.Mask" "F.Paste")
			(net "FM_TPM_PRSNT_RST_N")
			(options
				(clearance outline)
				(anchor circle)
			)
			(primitives
				(gr_poly
					(pts
						(arc
							(start -0.1778 -0.2794)
							(mid -0.249642 -0.249642)
							(end -0.2794 -0.1778)
						)
						(arc
							(start -0.2794 0.1778)
							(mid -0.249642 0.249642)
							(end -0.1778 0.2794)
						)
						(arc
							(start 0.1778 0.2794)
							(mid 0.249642 0.249642)
							(end 0.2794 0.1778)
						)
						(arc
							(start 0.2794 -0.1778)
							(mid 0.249642 -0.249642)
							(end 0.1778 -0.2794)
						)
					)
					(width 0)
					(fill yes)
				)
			)
		)
	)
	(footprint ""
		(layer "F.Cu")
		(at 27.559 -122.047 180)
		(property "Reference" "R84"
			(at 0 0 180)
			(layer "F.SilkS")
			(hide yes)
			(effects
				(font
					(size 1.27 1.27)
				)
			)
		)
		(property "Value" "4K7R2F-GP"
			(at 0.064008 -3.993896 180)
			(unlocked yes)
			(layer "F.Fab")
			(hide yes)
			(effects
				(font
					(size 1.016 1.016)
					(thickness 0.1524)
				)
			)
		)
		(property "Device Type" "R402H16"
			(at 0.064008 -5.517896 180)
			(unlocked yes)
			(layer "F.Fab")
			(hide yes)
			(effects
				(font
					(size 1.016 1.016)
					(thickness 0.1524)
				)
			)
		)
		(duplicate_pad_numbers_are_jumpers no)
		(fp_line
			(start 0.508 -0.9398)
			(end -0.508 -0.9398)
			(stroke
				(width 0.1524)
				(type default)
			)
			(layer "F.SilkS")
		)
		(fp_line
			(start -0.508 -0.9398)
			(end -0.508 0.9398)
			(stroke
				(width 0.1524)
				(type default)
			)
			(layer "F.SilkS")
		)
		(fp_rect
			(start -0.508 0.9398)
			(end 0.508 -0.9398)
			(stroke
				(width 0)
				(type default)
			)
			(fill no)
			(layer "F.CrtYd")
		)
		(fp_rect
			(start -0.508 0.9398)
			(end 0.508 -0.9398)
			(stroke
				(width 0)
				(type default)
			)
			(fill no)
			(layer "F.Fab")
		)
		(pad "1" smd custom
			(at 0 -0.4445 180)
			(size 0.1397 0.1397)
			(layers "F.Cu" "F.Mask" "F.Paste")
			(net "P3V3_STBY")
			(options
				(clearance outline)
				(anchor circle)
			)
			(primitives
				(gr_poly
					(pts
						(arc
							(start -0.1778 -0.2794)
							(mid -0.249642 -0.249642)
							(end -0.2794 -0.1778)
						)
						(arc
							(start -0.2794 0.1778)
							(mid -0.249642 0.249642)
							(end -0.1778 0.2794)
						)
						(arc
							(start 0.1778 0.2794)
							(mid 0.249642 0.249642)
							(end 0.2794 0.1778)
						)
						(arc
							(start 0.2794 -0.1778)
							(mid 0.249642 -0.249642)
							(end 0.1778 -0.2794)
						)
					)
					(width 0)
					(fill yes)
				)
			)
		)
		(pad "2" smd custom
			(at 0 0.4445 180)
			(size 0.1397 0.1397)
			(layers "F.Cu" "F.Mask" "F.Paste")
			(net "WP_DISABLE")
			(options
				(clearance outline)
				(anchor circle)
			)
			(primitives
				(gr_poly
					(pts
						(arc
							(start -0.1778 -0.2794)
							(mid -0.249642 -0.249642)
							(end -0.2794 -0.1778)
						)
						(arc
							(start -0.2794 0.1778)
							(mid -0.249642 0.249642)
							(end -0.1778 0.2794)
						)
						(arc
							(start 0.1778 0.2794)
							(mid 0.249642 0.249642)
							(end 0.2794 0.1778)
						)
						(arc
							(start 0.2794 -0.1778)
							(mid 0.249642 -0.249642)
							(end 0.1778 -0.2794)
						)
					)
					(width 0)
					(fill yes)
				)
			)
		)
	)
	(footprint ""
		(layer "F.Cu")
		(at 98.5774 -143.3576 90)
		(property "Reference" "R428"
			(at 0 0 90)
			(layer "F.SilkS")
			(hide yes)
			(effects
				(font
					(size 1.27 1.27)
				)
			)
		)
		(property "Value" "4K7R2F-GP"
			(at 0.064008 -3.993896 90)
			(unlocked yes)
			(layer "F.Fab")
			(hide yes)
			(effects
				(font
					(size 1.016 1.016)
					(thickness 0.1524)
				)
			)
		)
		(property "Device Type" "R402H16"
			(at 0.064008 -5.517896 90)
			(unlocked yes)
			(layer "F.Fab")
			(hide yes)
			(effects
				(font
					(size 1.016 1.016)
					(thickness 0.1524)
				)
			)
		)
		(duplicate_pad_numbers_are_jumpers no)
		(fp_line
			(start 0.508 -0.9398)
			(end -0.508 -0.9398)
			(stroke
				(width 0.1524)
				(type default)
			)
			(layer "F.SilkS")
		)
		(fp_line
			(start -0.508 -0.9398)
			(end -0.508 0.9398)
			(stroke
				(width 0.1524)
				(type default)
			)
			(layer "F.SilkS")
		)
		(fp_rect
			(start -0.508 0.9398)
			(end 0.508 -0.9398)
			(stroke
				(width 0)
				(type default)
			)
			(fill no)
			(layer "F.CrtYd")
		)
		(fp_rect
			(start -0.508 0.9398)
			(end 0.508 -0.9398)
			(stroke
				(width 0)
				(type default)
			)
			(fill no)
			(layer "F.Fab")
		)
		(pad "1" smd custom
			(at 0 -0.4445 90)
			(size 0.1397 0.1397)
			(layers "F.Cu" "F.Mask" "F.Paste")
			(net "TCA9555_A0")
			(options
				(clearance outline)
				(anchor circle)
			)
			(primitives
				(gr_poly
					(pts
						(arc
							(start -0.1778 -0.2794)
							(mid -0.249642 -0.249642)
							(end -0.2794 -0.1778)
						)
						(arc
							(start -0.2794 0.1778)
							(mid -0.249642 0.249642)
							(end -0.1778 0.2794)
						)
						(arc
							(start 0.1778 0.2794)
							(mid 0.249642 0.249642)
							(end 0.2794 0.1778)
						)
						(arc
							(start 0.2794 -0.1778)
							(mid 0.249642 -0.249642)
							(end 0.1778 -0.2794)
						)
					)
					(width 0)
					(fill yes)
				)
			)
		)
		(pad "2" smd custom
			(at 0 0.4445 90)
			(size 0.1397 0.1397)
			(layers "F.Cu" "F.Mask" "F.Paste")
			(net "GND")
			(options
				(clearance outline)
				(anchor circle)
			)
			(primitives
				(gr_poly
					(pts
						(arc
							(start -0.1778 -0.2794)
							(mid -0.249642 -0.249642)
							(end -0.2794 -0.1778)
						)
						(arc
							(start -0.2794 0.1778)
							(mid -0.249642 0.249642)
							(end -0.1778 0.2794)
						)
						(arc
							(start 0.1778 0.2794)
							(mid 0.249642 0.249642)
							(end 0.2794 0.1778)
						)
						(arc
							(start 0.2794 -0.1778)
							(mid 0.249642 -0.249642)
							(end 0.1778 -0.2794)
						)
					)
					(width 0)
					(fill yes)
				)
			)
		)
	)
	(footprint ""
		(layer "F.Cu")
		(at 186.817 -108.4072 90)
		(property "Reference" "R553"
			(at 0 0 90)
			(layer "F.SilkS")
			(hide yes)
			(effects
				(font
					(size 1.27 1.27)
				)
			)
		)
		(property "Value" "4K7R2F-GP"
			(at 0.064008 -3.993896 90)
			(unlocked yes)
			(layer "F.Fab")
			(hide yes)
			(effects
				(font
					(size 1.016 1.016)
					(thickness 0.1524)
				)
			)
		)
		(property "Device Type" "R402H16"
			(at 0.064008 -5.517896 90)
			(unlocked yes)
			(layer "F.Fab")
			(hide yes)
			(effects
				(font
					(size 1.016 1.016)
					(thickness 0.1524)
				)
			)
		)
		(duplicate_pad_numbers_are_jumpers no)
		(fp_line
			(start 0.508 -0.9398)
			(end -0.508 -0.9398)
			(stroke
				(width 0.1524)
				(type default)
			)
			(layer "F.SilkS")
		)
		(fp_line
			(start -0.508 -0.9398)
			(end -0.508 0.9398)
			(stroke
				(width 0.1524)
				(type default)
			)
			(layer "F.SilkS")
		)
		(fp_rect
			(start -0.508 0.9398)
			(end 0.508 -0.9398)
			(stroke
				(width 0)
				(type default)
			)
			(fill no)
			(layer "F.CrtYd")
		)
		(fp_rect
			(start -0.508 0.9398)
			(end 0.508 -0.9398)
			(stroke
				(width 0)
				(type default)
			)
			(fill no)
			(layer "F.Fab")
		)
		(pad "1" smd custom
			(at 0 -0.4445 90)
			(size 0.1397 0.1397)
			(layers "F.Cu" "F.Mask" "F.Paste")
			(net "TEMP_1_A2")
			(options
				(clearance outline)
				(anchor circle)
			)
			(primitives
				(gr_poly
					(pts
						(arc
							(start -0.1778 -0.2794)
							(mid -0.249642 -0.249642)
							(end -0.2794 -0.1778)
						)
						(arc
							(start -0.2794 0.1778)
							(mid -0.249642 0.249642)
							(end -0.1778 0.2794)
						)
						(arc
							(start 0.1778 0.2794)
							(mid 0.249642 0.249642)
							(end 0.2794 0.1778)
						)
						(arc
							(start 0.2794 -0.1778)
							(mid 0.249642 -0.249642)
							(end 0.1778 -0.2794)
						)
					)
					(width 0)
					(fill yes)
				)
			)
		)
		(pad "2" smd custom
			(at 0 0.4445 90)
			(size 0.1397 0.1397)
			(layers "F.Cu" "F.Mask" "F.Paste")
			(net "GND")
			(options
				(clearance outline)
				(anchor circle)
			)
			(primitives
				(gr_poly
					(pts
						(arc
							(start -0.1778 -0.2794)
							(mid -0.249642 -0.249642)
							(end -0.2794 -0.1778)
						)
						(arc
							(start -0.2794 0.1778)
							(mid -0.249642 0.249642)
							(end -0.1778 0.2794)
						)
						(arc
							(start 0.1778 0.2794)
							(mid 0.249642 0.249642)
							(end 0.2794 0.1778)
						)
						(arc
							(start 0.2794 -0.1778)
							(mid 0.249642 -0.249642)
							(end 0.1778 -0.2794)
						)
					)
					(width 0)
					(fill yes)
				)
			)
		)
	)
	(footprint ""
		(layer "F.Cu")
		(at 166.585138 -9.171178)
		(property "Reference" "C217"
			(at 0 0 0)
			(layer "F.SilkS")
			(hide yes)
			(effects
				(font
					(size 1.27 1.27)
				)
			)
		)
		(property "Value" "SC10U6D3V5KX-4GP"
			(at -0.0762 -6.1214 0)
			(unlocked yes)
			(layer "F.Fab")
			(hide yes)
			(effects
				(font
					(size 1.016 1.016)
					(thickness 0.1524)
				)
			)
		)
		(property "Device Type" "C805H58"
			(at -0.0762 -8.1534 0)
			(unlocked yes)
			(layer "F.Fab")
			(hide yes)
			(effects
				(font
					(size 1.016 1.016)
					(thickness 0.1524)
				)
			)
		)
		(duplicate_pad_numbers_are_jumpers no)
		(fp_line
			(start 0.635 0)
			(end -0.635 0)
			(stroke
				(width 0.508)
				(type default)
			)
			(layer "F.SilkS")
		)
		(fp_rect
			(start -0.9652 1.778)
			(end 0.9652 -1.778)
			(stroke
				(width 0)
				(type default)
			)
			(fill no)
			(layer "F.CrtYd")
		)
		(fp_poly
			(pts
				(xy -0.9652 -1.778) (xy 0.9652 -1.778) (xy 0.9652 1.778) (xy -0.9652 1.778)
			)
			(stroke
				(width 0)
				(type default)
			)
			(fill no)
			(layer "F.Fab")
		)
		(pad "1" smd rect
			(at 0 -0.9652)
			(size 1.397 1.143)
			(layers "F.Cu" "F.Mask" "F.Paste")
			(net "P1V8_STBY")
		)
		(pad "2" smd rect
			(at 0 0.9652)
			(size 1.397 1.143)
			(layers "F.Cu" "F.Mask" "F.Paste")
			(net "GND")
		)
	)
	(footprint ""
		(layer "F.Cu")
		(at 210.928204 -122.666506)
		(property "Reference" "TP212"
			(at 0 0 0)
			(layer "F.SilkS")
			(hide yes)
			(effects
				(font
					(size 1.27 1.27)
				)
			)
		)
		(property "Value" "TPAD28-2-GP"
			(at -0.0127 -1.6637 0)
			(unlocked yes)
			(layer "F.Fab")
			(hide yes)
			(effects
				(font
					(size 1.016 1.016)
					(thickness 0.1524)
				)
			)
		)
		(property "Device Type" "TPAD28"
			(at -0.0127 -3.1877 0)
			(unlocked yes)
			(layer "F.Fab")
			(hide yes)
			(effects
				(font
					(size 1.016 1.016)
					(thickness 0.1524)
				)
			)
		)
		(duplicate_pad_numbers_are_jumpers no)
		(fp_poly
			(pts
				(arc
					(start 0.3556 0)
					(mid -0.3556 0)
					(end 0.3556 0)
				)
			)
			(stroke
				(width 0)
				(type default)
			)
			(fill no)
			(layer "F.CrtYd")
		)
		(fp_poly
			(pts
				(arc
					(start 0.6096 0)
					(mid -0.6096 0)
					(end 0.6096 0)
				)
			)
			(stroke
				(width 0)
				(type default)
			)
			(fill no)
			(layer "F.Fab")
		)
		(pad "1" smd circle
			(at 0 0)
			(size 0.7112 0.7112)
			(layers "F.Cu" "F.Mask" "F.Paste")
			(net "TP_M2_1_MFG_DAT")
		)
	)
	(footprint ""
		(layer "F.Cu")
		(at 199.1614 -6.35 90)
		(property "Reference" "R737"
			(at 0 0 90)
			(layer "F.SilkS")
			(hide yes)
			(effects
				(font
					(size 1.27 1.27)
				)
			)
		)
		(property "Value" "120R3F-L-GP"
			(at -0.0254 -2.5146 90)
			(unlocked yes)
			(layer "F.Fab")
			(hide yes)
			(effects
				(font
					(size 1.016 1.016)
					(thickness 0.1524)
				)
			)
		)
		(property "Device Type" "R603H22"
			(at -0.0254 -4.0386 90)
			(unlocked yes)
			(layer "F.Fab")
			(hide yes)
			(effects
				(font
					(size 1.016 1.016)
					(thickness 0.1524)
				)
			)
		)
		(duplicate_pad_numbers_are_jumpers no)
		(fp_line
			(start 0.2032 0)
			(end 0.4826 0)
			(stroke
				(width 0.2032)
				(type default)
			)
			(layer "F.SilkS")
		)
		(fp_line
			(start -0.4826 0)
			(end -0.2032 0)
			(stroke
				(width 0.2032)
				(type default)
			)
			(layer "F.SilkS")
		)
		(fp_rect
			(start -0.5842 1.3335)
			(end 0.5842 -1.3335)
			(stroke
				(width 0)
				(type default)
			)
			(fill no)
			(layer "F.CrtYd")
		)
		(fp_rect
			(start -0.5842 1.3335)
			(end 0.5842 -1.3335)
			(stroke
				(width 0)
				(type default)
			)
			(fill no)
			(layer "F.Fab")
		)
		(pad "1" smd custom
			(at 0 -0.762 90)
			(size 0.2159 0.2159)
			(layers "F.Cu" "F.Mask" "F.Paste")
			(net "ML_PWR_YELLOW_LED")
			(options
				(clearance outline)
				(anchor circle)
			)
			(primitives
				(gr_poly
					(pts
						(arc
							(start -0.3302 -0.4318)
							(mid -0.402042 -0.402042)
							(end -0.4318 -0.3302)
						)
						(arc
							(start -0.4318 0.3302)
							(mid -0.402042 0.402042)
							(end -0.3302 0.4318)
						)
						(arc
							(start 0.3302 0.4318)
							(mid 0.402042 0.402042)
							(end 0.4318 0.3302)
						)
						(arc
							(start 0.4318 -0.3302)
							(mid 0.402042 -0.402042)
							(end 0.3302 -0.4318)
						)
					)
					(width 0)
					(fill yes)
				)
			)
		)
		(pad "2" smd custom
			(at 0 0.762 90)
			(size 0.2159 0.2159)
			(layers "F.Cu" "F.Mask" "F.Paste")
			(net "ML_PWR_YELLOW_LED_R")
			(options
				(clearance outline)
				(anchor circle)
			)
			(primitives
				(gr_poly
					(pts
						(arc
							(start -0.3302 -0.4318)
							(mid -0.402042 -0.402042)
							(end -0.4318 -0.3302)
						)
						(arc
							(start -0.4318 0.3302)
							(mid -0.402042 0.402042)
							(end -0.3302 0.4318)
						)
						(arc
							(start 0.3302 0.4318)
							(mid 0.402042 0.402042)
							(end 0.4318 0.3302)
						)
						(arc
							(start 0.4318 -0.3302)
							(mid 0.402042 -0.402042)
							(end 0.3302 -0.4318)
						)
					)
					(width 0)
					(fill yes)
				)
			)
		)
	)
)
